(kicad_pcb
	(version 20221018)
	(generator pcbnew)
	(general
    (thickness 1.7403)
  )
	(paper "A4")
	(title_block
    (title "Data Center RDIMM DDR4 Tester")
    (date "2024-09-30")
    (rev "1.2.4")
		(comment 9 "footprints 330-336 of 690")
	)
	(layers
    (0 "F.Cu" signal)
    (1 "In1.Cu" power)
    (2 "In2.Cu" signal)
    (3 "In3.Cu" power)
    (4 "In4.Cu" power)
    (5 "In5.Cu" signal)
    (6 "In6.Cu" power)
    (7 "In7.Cu" signal)
    (8 "In8.Cu" power)
    (9 "In9.Cu" signal)
    (10 "In10.Cu" power)
    (31 "B.Cu" signal)
    (32 "B.Adhes" user "B.Adhesive")
    (33 "F.Adhes" user "F.Adhesive")
    (34 "B.Paste" user)
    (35 "F.Paste" user)
    (36 "B.SilkS" user "B.Silkscreen")
    (37 "F.SilkS" user "F.Silkscreen")
    (38 "B.Mask" user)
    (39 "F.Mask" user)
    (40 "Dwgs.User" user "User.Drawings")
    (41 "Cmts.User" user "User.Comments")
    (42 "Eco1.User" user "User.Eco1")
    (43 "Eco2.User" user "User.Eco2")
    (44 "Edge.Cuts" user)
    (45 "Margin" user)
    (46 "B.CrtYd" user "B.Courtyard")
    (47 "F.CrtYd" user "F.Courtyard")
    (48 "B.Fab" user)
    (49 "F.Fab" user)
  )
	(footprint "data-center-rdimm-ddr4-tester-footprints:SW_1-1825027-1_THT" (layer "F.Cu")
    (at 223.65 131.6725)
    (descr "Tactile Switches, Round Actuator Style, NO, 5.74mm")
    (property "Author" "Antmicro")
    (property "License" "Apache-2.0")
    (property "MPN" "1-1825027-1")
    (property "Manufacturer" "TE Connectivity")
    (property "Sheetfile" "interfaces.kicad_sch")
    (property "Sheetname" "Interfaces")
    (property "ki_description" "Tactile Switch, Side Actuated, Through Hole, Round Button, 160 gf, 50mA at 24VDC")
    (property "ki_keywords" "HORIZONTAL, SWITCH, THT, MECHANICAL, TACTILE")
    (attr through_hole)
    (fp_text reference "S1" (at 7.49 2.9475 90) (layer "F.SilkS")
        (effects (font (size 0.7 0.7) (thickness 0.15)) (justify left bottom))
    )
    (fp_text value "SW_1-1825027-1" (at -2.4 9.6) (layer "F.Fab")
        (effects (font (size 0.7 0.7) (thickness 0.15)) (justify left bottom))
    )
    (fp_text user "${REFERENCE}" (at -2.452 11) (layer "F.Fab") hide
        (effects (font (size 0.7 0.7) (thickness 0.15)) (justify left bottom))
    )
    (fp_text user "License: Apache-2.0" (at -2.452 13.88) (layer "F.Fab") hide
        (effects (font (size 0.7 0.7) (thickness 0.15)) (justify left bottom))
    )
    (fp_text user "Author: Antmicro" (at -2.452 12.4) (layer "F.Fab") hide
        (effects (font (size 0.7 0.7) (thickness 0.15)) (justify left bottom))
    )
    (fp_line (start -1.331 -4.01) (end 5.828 -4.01)
      (stroke (width 0.15) (type solid)) (layer "F.SilkS"))
    (fp_line (start -1.307 2.548) (end -1.307 -0.485)
      (stroke (width 0.15) (type solid)) (layer "F.SilkS"))
    (fp_line (start 4.004 2.6) (end 0.494 2.6)
      (stroke (width 0.15) (type solid)) (layer "F.SilkS"))
    (fp_line (start 5.804 -0.5) (end 5.799 2.6)
      (stroke (width 0.15) (type solid)) (layer "F.SilkS"))
    (fp_line (start -1.6 -4.21) (end -1.6 2.89)
      (stroke (width 0.05) (type solid)) (layer "F.CrtYd"))
    (fp_line (start -1.6 2.89) (end 0.14 2.89)
      (stroke (width 0.05) (type solid)) (layer "F.CrtYd"))
    (fp_line (start 0.14 2.89) (end 0.14 8.58)
      (stroke (width 0.05) (type solid)) (layer "F.CrtYd"))
    (fp_line (start 0.14 8.58) (end 4.24 8.58)
      (stroke (width 0.05) (type solid)) (layer "F.CrtYd"))
    (fp_line (start 4.24 2.89) (end 6.1 2.89)
      (stroke (width 0.05) (type solid)) (layer "F.CrtYd"))
    (fp_line (start 4.24 8.58) (end 4.24 2.89)
      (stroke (width 0.05) (type solid)) (layer "F.CrtYd"))
    (fp_line (start 6.1 -4.21) (end -1.6 -4.21)
      (stroke (width 0.05) (type solid)) (layer "F.CrtYd"))
    (fp_line (start 6.1 2.89) (end 6.1 -4.21)
      (stroke (width 0.05) (type solid)) (layer "F.CrtYd"))
    (fp_line (start -1.307 -4.01) (end 5.804 -4.01)
      (stroke (width 0.15) (type solid)) (layer "F.Fab"))
    (fp_line (start -1.307 2.6) (end -1.307 -4.01)
      (stroke (width 0.15) (type solid)) (layer "F.Fab"))
    (fp_line (start 0.494 2.6) (end -1.307 2.6)
      (stroke (width 0.15) (type solid)) (layer "F.Fab"))
    (fp_line (start 0.494 2.6) (end 0.494 8.349)
      (stroke (width 0.15) (type solid)) (layer "F.Fab"))
    (fp_line (start 0.494 8.349) (end 4.004 8.349)
      (stroke (width 0.15) (type solid)) (layer "F.Fab"))
    (fp_line (start 4.004 8.349) (end 3.999 2.6)
      (stroke (width 0.15) (type solid)) (layer "F.Fab"))
    (fp_line (start 5.799 2.6) (end 3.999 2.6)
      (stroke (width 0.15) (type solid)) (layer "F.Fab"))
    (fp_line (start 5.804 -4.01) (end 5.804 2.6)
      (stroke (width 0.15) (type solid)) (layer "F.Fab"))
    (pad "1" thru_hole circle (at 0 0) (size 1.498 1.498) (drill 0.99) (layers "*.Cu" "*.Mask")
      (net 149 "HOT_SWAP_BUTTON") (pinfunction "1") (pintype "passive"))
    (pad "2" thru_hole circle (at 4.498 0) (size 1.498 1.498) (drill 0.99) (layers "*.Cu" "*.Mask")
      (net 9 "GND") (pinfunction "2") (pintype "passive"))
    (pad "SH" thru_hole circle (at -1.256 -2.492) (size 1.95 1.95) (drill 1.3) (layers "*.Cu" "*.Mask")
      (net 9 "GND") (pinfunction "SH") (pintype "passive"))
    (pad "SH" thru_hole circle (at 5.754 -2.492) (size 1.95 1.95) (drill 1.3) (layers "*.Cu" "*.Mask")
      (net 9 "GND") (pinfunction "SH") (pintype "passive"))
  )
	(footprint "data-center-rdimm-ddr4-tester-footprints:R_0201" (layer "F.Cu")
    (at 157.8 109.03 -90)
    (descr "Resistor SMD 0201")
    (tags "resistor SMD 0201")
    (property "Author" "Antmicro")
    (property "License" "Apache-2.0")
    (property "MPN" "CR0201-FX-0R00GLF")
    (property "Manufacturer" "Bourns")
    (property "Sheetfile" "ethernet.kicad_sch")
    (property "Sheetname" "Ethernet")
    (property "Tolerance" "1%")
    (property "Val" "0R")
    (property "ki_description" "0R resistor in 0201 package with 1% tolerance")
    (attr smd)
    (fp_text reference "R107" (at 3.46 -0.22 -90) (layer "F.SilkS")
        (effects (font (size 0.7 0.7) (thickness 0.15)) (justify left bottom))
    )
    (fp_text value "R_0R_0201" (at 0 1.25 -90) (layer "F.Fab") hide
        (effects (font (size 0.7 0.7) (thickness 0.15)) (justify left bottom))
    )
    (fp_text user "${REFERENCE}" (at -0.71 3.25 -90) (layer "F.Fab") hide
        (effects (font (size 0.7 0.7) (thickness 0.15)) (justify left bottom))
    )
    (fp_text user "License: Apache-2.0" (at -0.71 4.25 -90) (layer "F.Fab") hide
        (effects (font (size 0.7 0.7) (thickness 0.15)) (justify left bottom))
    )
    (fp_text user "Author: Antmicro" (at -0.71 5.25 -90) (layer "F.Fab") hide
        (effects (font (size 0.7 0.7) (thickness 0.15)) (justify left bottom))
    )
    (fp_rect (start -0.71 -0.36) (end 0.71 0.36)
      (stroke (width 0.05) (type solid)) (fill none) (layer "F.CrtYd"))
    (fp_rect (start -0.3 -0.15) (end 0.298 0.148)
      (stroke (width 0.15) (type solid)) (fill none) (layer "F.Fab"))
    (pad "" smd roundrect (at -0.346 0 270) (size 0.318 0.36) (layers "F.Paste") (roundrect_rratio 0.25))
    (pad "" smd roundrect (at 0.344 0 270) (size 0.318 0.36) (layers "F.Paste") (roundrect_rratio 0.25))
    (pad "1" smd roundrect (at -0.32 0 270) (size 0.46 0.4) (layers "F.Cu" "F.Mask") (roundrect_rratio 0.25)
      (net 826 "/Ethernet/ETH2_BP_P") (pintype "passive"))
    (pad "2" smd roundrect (at 0.32 0 270) (size 0.46 0.4) (layers "F.Cu" "F.Mask") (roundrect_rratio 0.25)
      (net 568 "/Ethernet/INT_ETH2_P") (pintype "passive"))
  )
	(footprint "data-center-rdimm-ddr4-tester-footprints:C_0402_1005Metric" (layer "F.Cu")
    (at 153.65 108.09 -90)
    (descr "Capacitor SMD 0402")
    (tags "capacitor SMD 0402")
    (property "Author" "Antmicro")
    (property "DNP" "DNP")
    (property "Dielectric" "X5R")
    (property "License" "Apache-2.0")
    (property "MPN" "GRM155R61H104KE14D")
    (property "Manufacturer" "Murata")
    (property "Sheetfile" "ethernet.kicad_sch")
    (property "Sheetname" "Ethernet")
    (property "Val" "100n")
    (property "Voltage" "50V")
    (property "dnp" "")
    (property "exclude_from_bom" "")
    (property "ki_description" " ")
    (attr exclude_from_pos_files exclude_from_bom)
    (fp_text reference "C293" (at 1.6 -1.24 -90) (layer "F.SilkS")
        (effects (font (size 0.7 0.7) (thickness 0.15)) (justify left bottom))
    )
    (fp_text value "C_100n_0402" (at 0 1.4 -90) (layer "F.Fab") hide
        (effects (font (size 0.7 0.7) (thickness 0.15)) (justify left bottom))
    )
    (fp_text user "License: Apache-2.0" (at -0.932 5.17 -90) (layer "F.Fab") hide
        (effects (font (size 0.7 0.7) (thickness 0.15)) (justify left bottom))
    )
    (fp_text user "Author: Antmicro" (at -0.932 4.17 -90) (layer "F.Fab") hide
        (effects (font (size 0.7 0.7) (thickness 0.15)) (justify left bottom))
    )
    (fp_text user "${REFERENCE}" (at -0.932 3.168 -90) (layer "F.Fab") hide
        (effects (font (size 0.7 0.7) (thickness 0.15)) (justify left bottom))
    )
    (fp_rect (start -0.94 -0.47) (end 0.94 0.47)
      (stroke (width 0.05) (type solid)) (fill none) (layer "F.CrtYd"))
    (fp_rect (start -0.499 -0.249) (end 0.499 0.249)
      (stroke (width 0.15) (type solid)) (fill none) (layer "F.Fab"))
    (pad "1" smd roundrect (at -0.484 0 270) (size 0.59 0.64) (layers "F.Cu" "F.Paste" "F.Mask") (roundrect_rratio 0.25)
      (net 143 "3V3_SYS") (pintype "passive"))
    (pad "2" smd roundrect (at 0.484 0 270) (size 0.59 0.64) (layers "F.Cu" "F.Paste" "F.Mask") (roundrect_rratio 0.25)
      (net 9 "GND") (pintype "passive"))
  )
	(footprint "data-center-rdimm-ddr4-tester-footprints:C_0402_1005Metric" (layer "F.Cu")
    (at 254.71 86.795 180)
    (descr "Capacitor SMD 0402")
    (tags "capacitor SMD 0402")
    (property "Author" "Antmicro")
    (property "Dielectric" "X5R")
    (property "License" "Apache-2.0")
    (property "MPN" "GRM155R61H104KE14D")
    (property "Manufacturer" "Murata")
    (property "Sheetfile" "fmc_hpc.kicad_sch")
    (property "Sheetname" "FMC HPC")
    (property "Val" "100n")
    (property "Voltage" "50V")
    (property "ki_description" " ")
    (attr smd)
    (fp_text reference "C266" (at -0.8 -0.355 180) (layer "F.SilkS")
        (effects (font (size 0.7 0.7) (thickness 0.15)) (justify left bottom))
    )
    (fp_text value "C_100n_0402" (at 0 1.4 180) (layer "F.Fab") hide
        (effects (font (size 0.7 0.7) (thickness 0.15)) (justify left bottom))
    )
    (fp_text user "${REFERENCE}" (at -0.932 3.168 180) (layer "F.Fab") hide
        (effects (font (size 0.7 0.7) (thickness 0.15)) (justify left bottom))
    )
    (fp_text user "Author: Antmicro" (at -0.932 4.17 180) (layer "F.Fab") hide
        (effects (font (size 0.7 0.7) (thickness 0.15)) (justify left bottom))
    )
    (fp_text user "License: Apache-2.0" (at -0.932 5.17 180) (layer "F.Fab") hide
        (effects (font (size 0.7 0.7) (thickness 0.15)) (justify left bottom))
    )
    (fp_rect (start -0.94 -0.47) (end 0.94 0.47)
      (stroke (width 0.05) (type solid)) (fill none) (layer "F.CrtYd"))
    (fp_rect (start -0.499 -0.249) (end 0.499 0.249)
      (stroke (width 0.15) (type solid)) (fill none) (layer "F.Fab"))
    (pad "1" smd roundrect (at -0.484 0 180) (size 0.59 0.64) (layers "F.Cu" "F.Paste" "F.Mask") (roundrect_rratio 0.25)
      (net 451 "/FMC HPC/GTX_TX3_C_N") (pintype "passive"))
    (pad "2" smd roundrect (at 0.484 0 180) (size 0.59 0.64) (layers "F.Cu" "F.Paste" "F.Mask") (roundrect_rratio 0.25)
      (net 463 "GTX_TX3_N") (pintype "passive"))
  )
	(footprint "data-center-rdimm-ddr4-tester-footprints:NetTie-2_SMD_Pad0.127mm" (layer "F.Cu")
    (at 112.45 92.33 -90)
    (descr "Net tie, 2 pin, 0.127mm  SMD pads")
    (tags "net tie")
    (property "Author" "Antmicro")
    (property "License" "Apache-2.0")
    (property "MPN" "")
    (property "Manufacturer" "")
    (property "Sheetfile" "supply.kicad_sch")
    (property "Sheetname" "Supply")
    (property "ki_description" "Net tie, 2 pins")
    (property "ki_keywords" "net tie short")
    (attr through_hole exclude_from_pos_files)
    (net_tie_pad_groups "1, 2")
    (fp_text reference "NT3" (at -0.128 -1.345 -90) (layer "F.SilkS") hide
        (effects (font (size 0.7 0.7) (thickness 0.15)) (justify left bottom))
    )
    (fp_text value "Net-Tie_2" (at 0 1.199 -90) (layer "F.Fab") hide
        (effects (font (size 0.7 0.7) (thickness 0.15)) (justify left bottom))
    )
    (fp_text user "License: Apache-2.0" (at -0.128 5.6 -90) (layer "F.Fab") hide
        (effects (font (size 0.7 0.7) (thickness 0.15)) (justify left bottom))
    )
    (fp_text user "Author: Antmicro" (at -0.128 4.4 -90) (layer "F.Fab") hide
        (effects (font (size 0.7 0.7) (thickness 0.15)) (justify left bottom))
    )
    (fp_text user "${REFERENCE}" (at -0.128 3.2 -90) (layer "F.Fab") hide
        (effects (font (size 0.7 0.7) (thickness 0.15)) (justify left bottom))
    )
    (fp_poly
      (pts
        (xy -0.0635 -0.0635)
        (xy 0.0625 -0.0635)
        (xy 0.0625 0.0635)
        (xy -0.0635 0.0635)
      )

      (stroke (width 0) (type solid)) (fill solid) (layer "F.Cu"))
    (pad "1" smd roundrect (at -0.127 0 90) (size 0.127 0.127) (layers "F.Cu") (roundrect_rratio 0.5)
      (chamfer_ratio 0) (chamfer top_left bottom_left)
      (net 834 "/Supply/VTT_SEN_+") (pinfunction "1") (pintype "passive"))
    (pad "2" smd roundrect (at 0.126 0 270) (size 0.127 0.127) (layers "F.Cu") (roundrect_rratio 0.5)
      (chamfer_ratio 0) (chamfer top_left bottom_left)
      (net 299 "VCC0V6") (pinfunction "2") (pintype "passive"))
  )
	(footprint "data-center-rdimm-ddr4-tester-footprints:SOT-23-6" (layer "F.Cu")
    (at 229.55 122.8 90)
    (property "Author" "Antmicro")
    (property "License" "Apache-2.0")
    (property "MPN" "MAX16150AUT+T")
    (property "Manufacturer" "Maxim Integrated")
    (property "Sheetfile" "supply.kicad_sch")
    (property "Sheetname" "Supply")
    (property "ki_description" "nanoPower Pushbutton On/Off Controller and Battery Freshness Seal")
    (attr smd)
    (fp_text reference "U26" (at -2.06 1.58 180) (layer "F.SilkS")
        (effects (font (size 0.7 0.7) (thickness 0.15)) (justify left bottom))
    )
    (fp_text value "MAX16150A_SOT" (at -1.75 2.75 90) (layer "F.Fab") hide
        (effects (font (size 0.7 0.7) (thickness 0.15)) (justify left bottom))
    )
    (fp_text user "." (at -1.4 1.2 270) (layer "F.SilkS")
        (effects (font (size 1 1) (thickness 0.15)))
    )
    (fp_text user "License: Apache-2.0" (at -1.75 6.5 90) (layer "F.Fab") hide
        (effects (font (size 0.7 0.7) (thickness 0.15)) (justify left bottom))
    )
    (fp_text user "Author: Antmicro" (at -1.829 5.25 90) (layer "F.Fab") hide
        (effects (font (size 0.7 0.7) (thickness 0.15)) (justify left bottom))
    )
    (fp_text user "${REFERENCE}" (at -1.75 4 90) (layer "F.Fab") hide
        (effects (font (size 0.7 0.7) (thickness 0.15)) (justify left bottom))
    )
    (fp_line (start -1.45 -0.7) (end -1.45 -0.4)
      (stroke (width 0.12) (type solid)) (layer "F.SilkS"))
    (fp_line (start -1.45 0.7) (end -1.45 0.4)
      (stroke (width 0.12) (type solid)) (layer "F.SilkS"))
    (fp_line (start -1.3 -0.7) (end -1.45 -0.7)
      (stroke (width 0.12) (type solid)) (layer "F.SilkS"))
    (fp_line (start 1.3 -0.7) (end 1.45 -0.7)
      (stroke (width 0.12) (type solid)) (layer "F.SilkS"))
    (fp_line (start 1.3 0.7) (end 1.45 0.7)
      (stroke (width 0.12) (type solid)) (layer "F.SilkS"))
    (fp_line (start 1.45 -0.7) (end 1.45 -0.4)
      (stroke (width 0.12) (type solid)) (layer "F.SilkS"))
    (fp_line (start 1.45 0.7) (end 1.45 0.4)
      (stroke (width 0.12) (type solid)) (layer "F.SilkS"))
    (fp_rect (start -1.55 -1.85) (end 1.55 1.75)
      (stroke (width 0.05) (type solid)) (fill none) (layer "F.CrtYd"))
    (fp_line (start -1.5 -0.7) (end 1.5 -0.7)
      (stroke (width 0.1) (type solid)) (layer "F.Fab"))
    (fp_line (start -1.5 0.7) (end -1.5 -0.7)
      (stroke (width 0.1) (type solid)) (layer "F.Fab"))
    (fp_line (start 1.5 -0.7) (end 1.5 0.7)
      (stroke (width 0.1) (type solid)) (layer "F.Fab"))
    (fp_line (start 1.5 0.7) (end -1.5 0.7)
      (stroke (width 0.1) (type solid)) (layer "F.Fab"))
    (pad "1" smd roundrect (at -0.954 1.1 90) (size 0.55 1) (layers "F.Cu" "F.Paste" "F.Mask") (roundrect_rratio 0.15)
      (net 664 "Net-(U26-~{PB_IN})") (pinfunction "~{PB_IN}") (pintype "input"))
    (pad "2" smd roundrect (at -0.003 1.1 90) (size 0.55 1) (layers "F.Cu" "F.Paste" "F.Mask") (roundrect_rratio 0.15)
      (net 9 "GND") (pinfunction "GND") (pintype "power_in"))
    (pad "3" smd roundrect (at 0.947 1.1 90) (size 0.55 1) (layers "F.Cu" "F.Paste" "F.Mask") (roundrect_rratio 0.15)
      (net 846 "5V_ON_OFF") (pinfunction "VCC") (pintype "power_in"))
    (pad "4" smd roundrect (at 0.947 -1.214 90) (size 0.55 1) (layers "F.Cu" "F.Paste" "F.Mask") (roundrect_rratio 0.15)
      (net 859 "/Supply/OUT") (pinfunction "OUT") (pintype "output"))
    (pad "5" smd roundrect (at -0.003 -1.214 90) (size 0.55 1) (layers "F.Cu" "F.Paste" "F.Mask") (roundrect_rratio 0.15)
      (net 119 "/Supply/~{INT}") (pinfunction "~{INT}") (pintype "output"))
    (pad "6" smd roundrect (at -0.954 -1.214 90) (size 0.55 1) (layers "F.Cu" "F.Paste" "F.Mask") (roundrect_rratio 0.15)
      (net 860 "/Supply/~{CLR}") (pinfunction "~{CLR}") (pintype "input"))
  )
	(footprint "data-center-rdimm-ddr4-tester-footprints:R_0201" (layer "F.Cu")
    (at 155.275 109.03 -90)
    (descr "Resistor SMD 0201")
    (tags "resistor SMD 0201")
    (property "Author" "Antmicro")
    (property "License" "Apache-2.0")
    (property "MPN" "CR0201-FX-0R00GLF")
    (property "Manufacturer" "Bourns")
    (property "Sheetfile" "ethernet.kicad_sch")
    (property "Sheetname" "Ethernet")
    (property "Tolerance" "1%")
    (property "Val" "0R")
    (property "ki_description" "0R resistor in 0201 package with 1% tolerance")
    (attr smd)
    (fp_text reference "R105" (at 3.49 -0.275 -90) (layer "F.SilkS")
        (effects (font (size 0.7 0.7) (thickness 0.15)) (justify left bottom))
    )
    (fp_text value "R_0R_0201" (at 0 1.25 -90) (layer "F.Fab") hide
        (effects (font (size 0.7 0.7) (thickness 0.15)) (justify left bottom))
    )
    (fp_text user "License: Apache-2.0" (at -0.71 4.25 -90) (layer "F.Fab") hide
        (effects (font (size 0.7 0.7) (thickness 0.15)) (justify left bottom))
    )
    (fp_text user "Author: Antmicro" (at -0.71 5.25 -90) (layer "F.Fab") hide
        (effects (font (size 0.7 0.7) (thickness 0.15)) (justify left bottom))
    )
    (fp_text user "${REFERENCE}" (at -0.71 3.25 -90) (layer "F.Fab") hide
        (effects (font (size 0.7 0.7) (thickness 0.15)) (justify left bottom))
    )
    (fp_rect (start -0.71 -0.36) (end 0.71 0.36)
      (stroke (width 0.05) (type solid)) (fill none) (layer "F.CrtYd"))
    (fp_rect (start -0.3 -0.15) (end 0.298 0.148)
      (stroke (width 0.15) (type solid)) (fill none) (layer "F.Fab"))
    (pad "" smd roundrect (at -0.346 0 270) (size 0.318 0.36) (layers "F.Paste") (roundrect_rratio 0.25))
    (pad "" smd roundrect (at 0.344 0 270) (size 0.318 0.36) (layers "F.Paste") (roundrect_rratio 0.25))
    (pad "1" smd roundrect (at -0.32 0 270) (size 0.46 0.4) (layers "F.Cu" "F.Mask") (roundrect_rratio 0.25)
      (net 824 "/Ethernet/ETH1_BP_P") (pintype "passive"))
    (pad "2" smd roundrect (at 0.32 0 270) (size 0.46 0.4) (layers "F.Cu" "F.Mask") (roundrect_rratio 0.25)
      (net 631 "/Ethernet/INT_ETH1_P") (pintype "passive"))
  )
)
